FILE_TYPE = CONNECTIVITY;
{Allegro Design Entry HDL 17.2-2016 S081 (4005846) 1/11/2022}
"PAGE_NUMBER" = 164;
0"NC";
1"GND\g";
2"GND\g";
3"GND\g";
4"GND\g";
5"P5V_AUX_VCC\G";
6"GND\g";
7"GND\g";
8"PWRGD_P5V_AUX_R";
9"SW_P5V_AUX_SW";
10"GND\g";
11"P5V_AUX_FB";
12"GND\g";
13"P12V_AUX\g";
14"P5V_AUX\g";
15"P5V_AUX_VCC\g";
16"GND\g";
17"SW_P5V_AUX_FLT";
18"PWRGD_P5V_AUX";
19"SW_P5V_AUX_BST";
20"P5V_AUX_REF";
21"GND\g";
22"PWRGD_P3V3_AUX";
23"P5V_AUX_CS";
24"P5V_AUX_MODE";
%"Q_CAP"
"1","(-8250,7825)","0","pure_quanta","I1";
;
LOCATION"PC1648"
$SEC"1"
CDS_SEC"1"
VALUE"100NF"
PACK_TYPE"C0402"
VOLTAGE"50V"
TOLERANCE"10%"
MATERIAL"X7R"
PART_NUMBER"CH4106K1B01"
CDS_LIB"pure_quanta";
"B"
$PN"2"2;
"A"
$PN"1"13;
%"Q_CAP"
"1","(-6900,6525)","2","pure_quanta","I10";
;
LOCATION"PC1848"
SEC"1"
VALUE"1UF"
VOLTAGE"25V"
PACK_TYPE"C0402"
MATERIAL"X6S"
TOLERANCE"10%"
PART_NUMBER"CH5104KEB02"
SEC_TYPE"C0402"
SIGNAL_MODEL"DEFAULT_CAPACITOR_100000PF_2_1"
CDS_LIB"pure_quanta";
"B"
$PN"2"6;
"A"
$PN"1"15;
%"UNIVERSAL_POWER"
"1","(-6900,7025)","0","pure_quanta_power","I11";
;
HDL_POWER"P5V_AUX_VCC"
CDS_LIB"pure_quanta_power";
"A"15;
%"Q_CAP"
"1","(-7075,7800)","0","pure_quanta","I12";
;
LOCATION"PC1850"
$SEC"1"
CDS_SEC"1"
PART_NUMBER"CH6223MEA01"
VALUE"22UF"
MATERIAL"X6S"
TOLERANCE"20%"
VOLTAGE"16V"
PACK_TYPE"C0805"
CDS_LIB"pure_quanta";
"B"
$PN"2"16;
"A"
$PN"1"17;
%"Q_CAP"
"1","(-6625,7800)","0","pure_quanta","I13";
;
LOCATION"PC1898"
$SEC"1"
CDS_SEC"1"
MATERIAL"X6S"
PACK_TYPE"C0805"
TOLERANCE"20%"
VALUE"22UF"
VOLTAGE"16V"
PART_NUMBER"CH6223MEA01"
CDS_LIB"pure_quanta";
"B"
$PN"2"16;
"A"
$PN"1"17;
%"Q_RES"
"1","(-6050,6950)","0","pure_quanta","I15";
;
LOCATION"PR3337"
$SEC"1"
CDS_SEC"1"
PART_NUMBER"CS00002JB13"
PACK_TYPE"0402LF"
VALUE"0"
TOLERANCE"5%"
MATERIAL"CHIP"
WATTAGE"1/16W"
CDS_LIB"pure_quanta";
"B"
$PN"2"1;
"A"
$PN"1"24;
%"MPQ8633AGLEC807Z"
"1","(-5075,7075)","0","pure_quanta","I16";
;
$LOCATION"U326"
CDS_LOCATION"U326"
$SEC"1"
CDS_SEC"1"
PART_TYPE"SMLF"
PART_NUMBER"AL008633007"
MATERIAL"IC"
VALUE"MPQ8633AGLE-C807-Z"
NEEDS_NO_SIZE"TRUE"
CDS_LMAN_SYM_OUTLINE"-250,725,250,-725"
CDS_LIB"pure_quanta";
"VIN2"
$PN"21"17;
"CS"
$PN"3"23;
"MODE"
$PN"4"24;
"TRK_REF"
$PN"5"20;
"SW"
$PN"20"9;
"RGND"
$PN"6"12;
"VCC"
$PN"19"15;
"AGND"
$PN"2"21;
"FB"
$PN"7"11;
"BST"
$PN"1"19;
"EN"
$PN"8"22;
"PGND"
$PN"11_18"21;
"PGOOD"
$PN"9"8;
"VIN1"
$PN"10"17;
%"GND"
"1","(-5650,6875)","0","pure_quanta_power","I17";
;
SIZE"1B"
CDS_LIB"pure_quanta_power"
HDL_POWER"GND";
"A<SIZE-1..0>\NAC"1;
%"Q_CAP"
"1","(-6225,7800)","0","pure_quanta","I18";
;
LOCATION"PC1846"
$SEC"1"
CDS_SEC"1"
VALUE"1UF"
PART_NUMBER"CH5103KEB01"
VOLTAGE"16V"
TOLERANCE"10%"
MATERIAL"X6S"
PACK_TYPE"C0402"
CDS_LIB"pure_quanta";
"B"
$PN"2"16;
"A"
$PN"1"17;
%"GND"
"1","(-4450,6125)","0","pure_quanta_power","I19";
;
CDS_LIB"pure_quanta_power"
SIZE"1B"
HDL_POWER"GND";
"A<SIZE-1..0>\NAC"21;
%"GND"
"1","(-8250,7575)","0","pure_quanta_power","I2";
;
CDS_LIB"pure_quanta_power"
SIZE"1B"
HDL_POWER"GND";
"A<SIZE-1..0>\NAC"2;
%"GND"
"1","(-4325,6125)","0","pure_quanta_power","I20";
;
CDS_LIB"pure_quanta_power"
SIZE"1B"
HDL_POWER"GND";
"A<SIZE-1..0>\NAC"3;
%"GND"
"1","(-3900,6200)","0","pure_quanta_power","I21";
;
CDS_LIB"pure_quanta_power"
SIZE"1B"
HDL_POWER"GND";
"A<SIZE-1..0>\NAC"12;
%"GND"
"1","(-3750,6200)","0","pure_quanta_power","I22";
;
CDS_LIB"pure_quanta_power"
SIZE"1B"
HDL_POWER"GND";
"A<SIZE-1..0>\NAC"4;
%"Q_CAP"
"1","(-4325,6350)","0","pure_quanta","I23";
;
LOCATION"PC1853"
$SEC"1"
CDS_SEC"1"
VALUE"0.1UF"
VOLTAGE"25V"
PACK_TYPE"0402"
TOLERANCE"10%"
MATERIAL"X7R"
PART_NUMBER"CH4104K1B00"
CDS_LIB"pure_quanta";
"B"
$PN"2"3;
"A"
$PN"1"20;
%"Q_RES"
"2","(-3750,6525)","0","pure_quanta","I24";
;
LOCATION"PR702"
$SEC"1"
CDS_SEC"1"
WATTAGE"1/16W"
PACK_TYPE"0402LF"
TOLERANCE"0.1%"
VALUE"11.8K"
PART_NUMBER"CS31182BB06"
MATERIAL"CHIP"
CDS_LIB"pure_quanta";
"A"
$PN"1"11;
"B"
$PN"2"4;
%"Q_CAP"
"1","(-3800,7400)","0","pure_quanta","I25";
;
LOCATION"PC1847"
$SEC"1"
CDS_SEC"1"
VOLTAGE"25V"
PACK_TYPE"C0402"
MATERIAL"X7R"
TOLERANCE"10%"
PART_NUMBER"CH4224K1B01"
VALUE"0.22UF"
CDS_LIB"pure_quanta";
"B"
$PN"2"9;
"A"
$PN"1"19;
%"Q_RES"
"2","(-3800,8125)","0","pure_quanta","I26";
;
LOCATION"R2356"
SEC"1"
PACK_TYPE"0402LF"
VALUE"10K"
WATTAGE"1/16W"
MATERIAL"CHIP"
PART_NUMBER"CS31002FB08"
TOLERANCE"1%"
SEC_TYPE"0402LF"
CDS_LIB"pure_quanta";
"A"
$PN"1"5;
"B"
$PN"2"8;
%"Q_RES"
"1","(-3225,7750)","0","pure_quanta","I27";
;
LOCATION"R2316"
$SEC"1"
CDS_SEC"1"
PACK_TYPE"0402LF"
TOLERANCE"5%"
MATERIAL"CHIP"
WATTAGE"1/16W"
VALUE"0"
PART_NUMBER"CS00002JB13"
CDS_LIB"pure_quanta";
"B"
$PN"2"18;
"A"
$PN"1"8;
%"Q_CAP"
"2","(-2400,6125)","0","pure_quanta","I28";
;
LOCATION"PC1877"
$SEC"1"
CDS_SEC"1"
PART_NUMBER"TMP_QCH04706JB01"
VALUE"47PF"
VOLTAGE"50V"
PACK_TYPE"0402"
TOLERANCE"5%"
MATERIAL"NPO"
CDS_LIB"pure_quanta";
"A"
$PN"1"11;
"B"
$PN"2"14;
%"Q_RES"
"1","(-2375,6450)","0","pure_quanta","I29";
;
LOCATION"PR703"
$SEC"1"
CDS_SEC"1"
VALUE"86.6K"
PART_NUMBER"CS38662FB05"
MATERIAL"CHIP"
TOLERANCE"1%"
PACK_TYPE"0402LF"
CDS_LIB"pure_quanta"
WATTAGE"1/16W";
"B"
$PN"2"14;
"A"
$PN"1"11;
%"P1V0_AUX"
"1","(-8246,8245)","0","pure_quanta_power","I3";
;
HDL_POWER"P12V_AUX"
ROOM"VR_DDR1_POWER_STAGE"
CDS_LIB"pure_quanta_power";
"A"13;
%"Q_INDUCTOR"
"1","(-2900,7275)","0","pure_quanta","I30";
;
LOCATION"PL81"
$SEC"1"
CDS_SEC"1"
PACK_TYPE"SMLF"
VALUE"4.7UH"
PART_NUMBER"CV-47A0MZ10"
MATERIAL"IND"
NEEDS_NO_SIZE"TRUE"
CDS_LIB"pure_quanta";
"1"
$PN"1"9;
"2"
$PN"2"14;
%"Q_CAPP"
"1","(-1625,7000)","0","pure_quanta","I31";
;
LOCATION"PC1845"
$SEC"1"
CDS_SEC"1"
MATERIAL"ALUM"
PART_NUMBER"CC72201MZ28"
TOLERANCE"20%"
VOLTAGE"6.3V"
PACK_TYPE"SMLF"
VALUE"220UF"
CDS_LIB"pure_quanta";
"A"
$PN"1"14;
"B"
$PN"2"10;
%"UNIVERSAL_POWER"
"1","(-3800,8425)","0","pure_quanta_power","I33";
;
HDL_POWER"P5V_AUX_VCC"
CDS_LIB"pure_quanta_power";
"A"5;
%"Q_CAP"
"1","(-1175,7000)","0","pure_quanta","I34";
;
LOCATION"PC1855"
$SEC"1"
CDS_SEC"1"
PART_NUMBER"CH6222MEA01"
VALUE"22UF"
PACK_TYPE"C0805"
TOLERANCE"20%"
VOLTAGE"10V"
MATERIAL"X6S"
CDS_LIB"pure_quanta";
"B"
$PN"2"10;
"A"
$PN"1"14;
%"Q_CAP"
"1","(-675,7000)","0","pure_quanta","I35";
;
LOCATION"PC1856"
$SEC"1"
CDS_SEC"1"
PART_NUMBER"CH6222MEA01"
MATERIAL"X6S"
PACK_TYPE"C0805"
VALUE"22UF"
VOLTAGE"10V"
TOLERANCE"20%"
CDS_LIB"pure_quanta";
"B"
$PN"2"10;
"A"
$PN"1"14;
%"GND"
"1","(-250,6600)","0","pure_quanta_power","I36";
;
CDS_LIB"pure_quanta_power"
SIZE"1B"
HDL_POWER"GND";
"A<SIZE-1..0>\NAC"10;
%"Q_CAP"
"1","(-250,7000)","0","pure_quanta","I37";
;
LOCATION"PC1852"
SEC"1"
PACK_TYPE"0402"
PART_NUMBER"CH4104K1B00"
MATERIAL"X7R"
TOLERANCE"10%"
VALUE"0.1UF"
VOLTAGE"25V"
CDS_LIB"pure_quanta"
SEC_TYPE"0402";
"B"
$PN"2"10;
"A"
$PN"1"14;
%"P1V0"
"1","(250,7725)","0","pure_quanta_power","I38";
;
HDL_POWER"P5V_AUX"
CDS_LIB"pure_quanta_power";
"A"14;
%"Q_INDUCTOR"
"1","(-7975,8050)","0","pure_quanta","I4";
;
LOCATION"PL80"
$SEC"1"
CDS_SEC"1"
MATERIAL"IND"
PACK_TYPE"SMLF"
VALUE"BLM18SN220TN1D/8000MA"
PART_NUMBER"CX220TN1001"
NEEDS_NO_SIZE"TRUE"
CDS_LIB"pure_quanta";
"1"
$PN"1"13;
"2"
$PN"2"17;
%"GND"
"1","(-7475,7425)","0","pure_quanta_power","I5";
;
CDS_LIB"pure_quanta_power"
SIZE"1B"
HDL_POWER"GND";
"A<SIZE-1..0>\NAC"16;
%"Q_CAP"
"1","(-7475,7800)","0","pure_quanta","I6";
;
LOCATION"PC1849"
$SEC"1"
CDS_SEC"1"
VALUE"22UF"
VOLTAGE"16V"
MATERIAL"X6S"
PART_NUMBER"CH6223MEA01"
PACK_TYPE"C0805"
TOLERANCE"20%"
CDS_LIB"pure_quanta";
"B"
$PN"2"16;
"A"
$PN"1"17;
%"GND"
"1","(-6900,6150)","0","pure_quanta_power","I7";
;
SIZE"1B"
CDS_LIB"pure_quanta_power"
HDL_POWER"GND";
"A<SIZE-1..0>\NAC"6;
%"GND"
"1","(-5962,5943)","0","pure_quanta_power","I8";
;
CDS_LIB"pure_quanta_power"
SIZE"1B"
HDL_POWER"GND";
"A<SIZE-1..0>\NAC"7;
%"Q_RES"
"2","(-5962,6232)","0","pure_quanta","I9";
;
LOCATION"PR701"
SEC"1"
WATTAGE"1/16W"
MATERIAL"CHIP"
TOLERANCE"1%"
VALUE"16.9K"
PACK_TYPE"0402LF"
PART_NUMBER"CS31692FB03"
CDS_LIB"pure_quanta"
SEC_TYPE"0402LF";
"A"
$PN"1"23;
"B"
$PN"2"7;
END.
